# T6G (Grand Teton) — schematic netlist excerpt (pin names and nets, part order shuffled) for the footprints in the layout excerpt that follows; sources: Cadence DE-HDL packaged netlist, KiCad conversion of 04192023_DAF0TMB3IC0_F0TG_MB_C_brd_V02_OCP.brd

PR3857  Q_RES  49.9 1% CHIP  pkg 0603LF  page 141 : A = P12V_AUX ; B = P12V_OCP_AVIN_PD_2
PR426  Q_RES  8.87K 1% EMPTY  pkg 0402LF  page 220 : A = PVDDCR_CPU1_P1_LSET6 ; B = GND

(kicad_pcb
	(version 20260206)
	(generator "pcbnew")
	(generator_version "10.0")
	(general
		(thickness 1.6)
		(legacy_teardrops no)
	)
	(paper "A4")
	(title_block
		(title "04192023_DAF0TMB3IC0_F0TG_MB_C_brd_V02_OCP.brd")
		(comment 1 "Grand Teton / footprints 1319-1320 of 8354")
	)
	(layers
		(0 "F.Cu" signal "TOP")
		(4 "In1.Cu" signal "GND")
		(6 "In2.Cu" signal "IN1")
		(8 "In3.Cu" signal "GND1")
		(10 "In4.Cu" signal "IN2")
		(12 "In5.Cu" signal "GND2")
		(14 "In6.Cu" signal "IN3")
		(16 "In7.Cu" signal "GND3")
		(18 "In8.Cu" signal "VCC")
		(20 "In9.Cu" signal "VCC1")
		(22 "In10.Cu" signal "GND4")
		(24 "In11.Cu" signal "IN4")
		(26 "In12.Cu" signal "GND5")
		(28 "In13.Cu" signal "IN5")
		(30 "In14.Cu" signal "GND6")
		(32 "In15.Cu" signal "IN6")
		(34 "In16.Cu" signal "GND7")
		(2 "B.Cu" signal "BOTTOM")
		(9 "F.Adhes" user "F.Adhesive")
		(11 "B.Adhes" user "B.Adhesive")
		(13 "F.Paste" user "Package Geometry/Pastemask Top")
		(15 "B.Paste" user "Package Geometry/Pastemask Bottom")
		(5 "F.SilkS" user "Ref Des/Silkscreen Top")
		(7 "B.SilkS" user "Ref Des/Silkscreen Bottom")
		(1 "F.Mask" user "Board Geometry/Soldermask Top")
		(3 "B.Mask" user "Board Geometry/Soldermask Bottom")
		(17 "Dwgs.User" user "User.Drawings")
		(19 "Cmts.User" user "User.Comments")
		(21 "Eco1.User" user "User.Eco1")
		(23 "Eco2.User" user "User.Eco2")
		(25 "Edge.Cuts" user "Board Geometry/Outline")
		(27 "Margin" user)
		(31 "F.CrtYd" user "Package Geometry/Place Bound Top")
		(29 "B.CrtYd" user "Package Geometry/Place Bound Bottom")
		(35 "F.Fab" user "Ref Des/Assembly Top")
		(33 "B.Fab" user "Ref Des/Assembly Bottom")
	)
	(footprint ""
		(layer "F.Cu")
		(at 102.424738 -345.150948)
		(property "Reference" "PR426"
			(at 0 0 0)
			(layer "F.SilkS")
			(hide yes)
			(effects
				(font
					(size 1.27 1.27)
				)
			)
		)
		(property "Value" ""
			(at 0 0 0)
			(layer "F.Fab")
			(effects
				(font
					(size 1.27 1.27)
				)
			)
		)
		(duplicate_pad_numbers_are_jumpers no)
		(fp_line
			(start -0.7874 -0.4064)
			(end 0.7874 -0.4064)
			(stroke
				(width 0.1524)
				(type default)
			)
			(layer "F.SilkS")
		)
		(fp_line
			(start -0.7874 0.4064)
			(end -0.7874 -0.4064)
			(stroke
				(width 0.1524)
				(type default)
			)
			(layer "F.SilkS")
		)
		(fp_line
			(start 0.7874 -0.4064)
			(end 0.7874 0.4064)
			(stroke
				(width 0.1524)
				(type default)
			)
			(layer "F.SilkS")
		)
		(fp_line
			(start 0.7874 0.4064)
			(end -0.7874 0.4064)
			(stroke
				(width 0.1524)
				(type default)
			)
			(layer "F.SilkS")
		)
		(fp_line
			(start -0.67945 -0.305054)
			(end -0.12065 -0.305054)
			(stroke
				(width 0.1)
				(type default)
			)
			(layer "F.Fab")
		)
		(fp_line
			(start -0.67945 0.3048)
			(end -0.67945 -0.305054)
			(stroke
				(width 0.1)
				(type default)
			)
			(layer "F.Fab")
		)
		(fp_line
			(start -0.12065 -0.305054)
			(end -0.12065 -0.2794)
			(stroke
				(width 0.1)
				(type default)
			)
			(layer "F.Fab")
		)
		(fp_line
			(start -0.12065 -0.2794)
			(end 0.12065 -0.2794)
			(stroke
				(width 0.1)
				(type default)
			)
			(layer "F.Fab")
		)
		(fp_line
			(start -0.12065 0.2794)
			(end -0.12065 0.3048)
			(stroke
				(width 0.1)
				(type default)
			)
			(layer "F.Fab")
		)
		(fp_line
			(start -0.12065 0.3048)
			(end -0.67945 0.3048)
			(stroke
				(width 0.1)
				(type default)
			)
			(layer "F.Fab")
		)
		(fp_line
			(start 0.120396 0.2794)
			(end -0.12065 0.2794)
			(stroke
				(width 0.1)
				(type default)
			)
			(layer "F.Fab")
		)
		(fp_line
			(start 0.120396 0.3048)
			(end 0.120396 0.2794)
			(stroke
				(width 0.1)
				(type default)
			)
			(layer "F.Fab")
		)
		(fp_line
			(start 0.12065 -0.3048)
			(end 0.67945 -0.3048)
			(stroke
				(width 0.1)
				(type default)
			)
			(layer "F.Fab")
		)
		(fp_line
			(start 0.12065 -0.2794)
			(end 0.12065 -0.3048)
			(stroke
				(width 0.1)
				(type default)
			)
			(layer "F.Fab")
		)
		(fp_line
			(start 0.67945 -0.3048)
			(end 0.67945 0.3048)
			(stroke
				(width 0.1)
				(type default)
			)
			(layer "F.Fab")
		)
		(fp_line
			(start 0.67945 0.3048)
			(end 0.120396 0.3048)
			(stroke
				(width 0.1)
				(type default)
			)
			(layer "F.Fab")
		)
		(pad "1" smd circle
			(at -0.40005 0)
			(size 0 0)
			(layers "F.Cu" "F.Mask" "F.Paste")
			(net "PVDDCR_CPU1_P1_LSET6")
		)
		(pad "2" smd circle
			(at 0.40005 0)
			(size 0 0)
			(layers "F.Cu" "F.Mask" "F.Paste")
			(net "GND")
		)
	)
	(footprint ""
		(layer "F.Cu")
		(at 64.614298 -23.554182)
		(property "Reference" "PR3857"
			(at 0 0 0)
			(layer "F.SilkS")
			(hide yes)
			(effects
				(font
					(size 1.27 1.27)
				)
			)
		)
		(property "Value" ""
			(at 0 0 0)
			(layer "F.Fab")
			(effects
				(font
					(size 1.27 1.27)
				)
			)
		)
		(duplicate_pad_numbers_are_jumpers no)
		(fp_line
			(start -1.2954 -0.5842)
			(end 1.2954 -0.5842)
			(stroke
				(width 0.1524)
				(type default)
			)
			(layer "F.SilkS")
		)
		(fp_line
			(start -1.2954 0.5842)
			(end -1.2954 -0.5842)
			(stroke
				(width 0.1524)
				(type default)
			)
			(layer "F.SilkS")
		)
		(fp_line
			(start 1.2954 -0.5842)
			(end 1.2954 0.5842)
			(stroke
				(width 0.1524)
				(type default)
			)
			(layer "F.SilkS")
		)
		(fp_line
			(start 1.2954 0.5842)
			(end -1.2954 0.5842)
			(stroke
				(width 0.1524)
				(type default)
			)
			(layer "F.SilkS")
		)
		(fp_line
			(start -1.1938 -0.406654)
			(end -0.8636 -0.406654)
			(stroke
				(width 0.1)
				(type default)
			)
			(layer "F.Fab")
		)
		(fp_line
			(start -1.1938 0.4064)
			(end -1.1938 -0.406654)
			(stroke
				(width 0.1)
				(type default)
			)
			(layer "F.Fab")
		)
		(fp_line
			(start -0.8636 -0.4572)
			(end 0.8636 -0.4572)
			(stroke
				(width 0.1)
				(type default)
			)
			(layer "F.Fab")
		)
		(fp_line
			(start -0.8636 -0.406654)
			(end -0.8636 -0.4572)
			(stroke
				(width 0.1)
				(type default)
			)
			(layer "F.Fab")
		)
		(fp_line
			(start -0.8636 0.4064)
			(end -1.1938 0.4064)
			(stroke
				(width 0.1)
				(type default)
			)
			(layer "F.Fab")
		)
		(fp_line
			(start -0.8636 0.4318)
			(end -0.8636 0.4064)
			(stroke
				(width 0.1)
				(type default)
			)
			(layer "F.Fab")
		)
		(fp_line
			(start -0.8636 0.4572)
			(end -0.8636 0.4318)
			(stroke
				(width 0.1)
				(type default)
			)
			(layer "F.Fab")
		)
		(fp_line
			(start 0.8636 -0.4572)
			(end 0.8636 -0.406654)
			(stroke
				(width 0.1)
				(type default)
			)
			(layer "F.Fab")
		)
		(fp_line
			(start 0.8636 -0.406654)
			(end 1.1938 -0.406654)
			(stroke
				(width 0.1)
				(type default)
			)
			(layer "F.Fab")
		)
		(fp_line
			(start 0.8636 0.4064)
			(end 0.8636 0.4572)
			(stroke
				(width 0.1)
				(type default)
			)
			(layer "F.Fab")
		)
		(fp_line
			(start 0.8636 0.4572)
			(end -0.8636 0.4572)
			(stroke
				(width 0.1)
				(type default)
			)
			(layer "F.Fab")
		)
		(fp_line
			(start 1.1938 -0.406654)
			(end 1.1938 0.4064)
			(stroke
				(width 0.1)
				(type default)
			)
			(layer "F.Fab")
		)
		(fp_line
			(start 1.1938 0.4064)
			(end 0.8636 0.4064)
			(stroke
				(width 0.1)
				(type default)
			)
			(layer "F.Fab")
		)
		(pad "1" smd rect
			(at -0.7366 0 270)
			(size 0.7112 0.8128)
			(layers "F.Cu" "F.Mask" "F.Paste")
			(net "P12V_AUX")
		)
		(pad "2" smd rect
			(at 0.7366 0 270)
			(size 0.7112 0.8128)
			(layers "F.Cu" "F.Mask" "F.Paste")
			(net "P12V_OCP_AVIN_PD_2")
		)
	)
)
